(kicad_pcb
	(version 20211014)
	(generator pcbnew)
	(general
    (thickness 1.6)
  )
	(paper "A4")
	(title_block
    (title "SA800U (Snapdragon 845) Baseboard")
    (date "2023-10-19")
    (rev "1.0.3")
    (company "Antmicro Ltd.")
    (comment 1 "www.antmicro.com")
		(comment 9 "footprints 536-549 of 589")
	)
	(layers
    (0 "F.Cu" signal)
    (1 "In1.Cu" power)
    (2 "In2.Cu" signal)
    (3 "In3.Cu" signal)
    (4 "In4.Cu" power)
    (31 "B.Cu" signal)
    (32 "B.Adhes" user "B.Adhesive")
    (33 "F.Adhes" user "F.Adhesive")
    (34 "B.Paste" user)
    (35 "F.Paste" user)
    (36 "B.SilkS" user "B.Silkscreen")
    (37 "F.SilkS" user "F.Silkscreen")
    (38 "B.Mask" user)
    (39 "F.Mask" user)
    (40 "Dwgs.User" user "User.Drawings")
    (41 "Cmts.User" user "User.Comments")
    (42 "Eco1.User" user "User.Eco1")
    (43 "Eco2.User" user "User.Eco2")
    (44 "Edge.Cuts" user)
    (45 "Margin" user)
    (46 "B.CrtYd" user "B.Courtyard")
    (47 "F.CrtYd" user "F.Courtyard")
    (48 "B.Fab" user)
    (49 "F.Fab" user)
  )
	(footprint "sa800u-baseboard-hw-footprints:TP_SMD_0.75mm" (layer "B.Cu")
    (tedit 5E4A9375)
    (at 72.85 84 180)
    (property "Author" "Antmicro")
    (property "License" "Apache-2.0")
    (property "MPN" "")
    (property "Manufacturer" "")
    (property "Sheetfile" "poe.kicad_sch")
    (property "Sheetname" "PoE")
    (attr smd)
    (fp_text reference "TP83" (at -1.21 0.57) (layer "B.SilkS")
      (effects (font (size 0.7 0.7) (thickness 0.15)) (justify left bottom mirror))
    )
    (fp_text value "TP_0.75mm_SMD" (at 0 -1.2) (layer "B.Fab")
      (effects (font (size 0.7 0.7) (thickness 0.15)) (justify left bottom mirror))
    )
    (fp_text user "Author: Antmicro" (at -0.4 -3.901) (layer "B.Fab") hide
      (effects (font (size 0.7 0.7) (thickness 0.15)) (justify left bottom mirror))
    )
    (fp_text user "License: Apache-2.0" (at -0.4 -5.101) (layer "B.Fab") hide
      (effects (font (size 0.7 0.7) (thickness 0.15)) (justify left bottom mirror))
    )
    (fp_text user "${REFERENCE}" (at -0.4 -2.7) (layer "B.Fab") hide
      (effects (font (size 0.7 0.7) (thickness 0.15)) (justify left bottom mirror))
    )
    (pad "1" smd circle (at 0 0 180) (size 0.75 0.75) (layers "B.Cu" "B.Mask")
      (net 153 "/PoE/TRIM") (pinfunction "1") (pintype "passive"))
  )
	(footprint "sa800u-baseboard-hw-footprints:TP_SMD_0.75mm" (layer "B.Cu")
    (tedit 5E4A9375)
    (at 75.25 84 180)
    (property "Author" "Antmicro")
    (property "License" "Apache-2.0")
    (property "MPN" "")
    (property "Manufacturer" "")
    (property "Sheetfile" "poe.kicad_sch")
    (property "Sheetname" "PoE")
    (attr smd)
    (fp_text reference "TP84" (at -1.51 0.53) (layer "B.SilkS")
      (effects (font (size 0.7 0.7) (thickness 0.15)) (justify left bottom mirror))
    )
    (fp_text value "TP_0.75mm_SMD" (at 0 -1.2) (layer "B.Fab")
      (effects (font (size 0.7 0.7) (thickness 0.15)) (justify left bottom mirror))
    )
    (fp_text user "Author: Antmicro" (at -0.4 -3.901) (layer "B.Fab") hide
      (effects (font (size 0.7 0.7) (thickness 0.15)) (justify left bottom mirror))
    )
    (fp_text user "${REFERENCE}" (at -0.4 -2.7) (layer "B.Fab") hide
      (effects (font (size 0.7 0.7) (thickness 0.15)) (justify left bottom mirror))
    )
    (fp_text user "License: Apache-2.0" (at -0.4 -5.101) (layer "B.Fab") hide
      (effects (font (size 0.7 0.7) (thickness 0.15)) (justify left bottom mirror))
    )
    (pad "1" smd circle (at 0 0 180) (size 0.75 0.75) (layers "B.Cu" "B.Mask")
      (net 136 "5V_POE") (pinfunction "1") (pintype "passive"))
  )
	(footprint "sa800u-baseboard-hw-footprints:TP_SMD_0.75mm" (layer "B.Cu")
    (tedit 5E4A9375)
    (at 70.25 84 180)
    (property "Author" "Antmicro")
    (property "License" "Apache-2.0")
    (property "MPN" "")
    (property "Manufacturer" "")
    (property "Sheetfile" "poe.kicad_sch")
    (property "Sheetname" "PoE")
    (attr smd)
    (fp_text reference "TP85" (at -1.16 0.59) (layer "B.SilkS")
      (effects (font (size 0.7 0.7) (thickness 0.15)) (justify left bottom mirror))
    )
    (fp_text value "TP_0.75mm_SMD" (at 0 -1.2) (layer "B.Fab")
      (effects (font (size 0.7 0.7) (thickness 0.15)) (justify left bottom mirror))
    )
    (fp_text user "${REFERENCE}" (at -0.4 -2.7) (layer "B.Fab") hide
      (effects (font (size 0.7 0.7) (thickness 0.15)) (justify left bottom mirror))
    )
    (fp_text user "Author: Antmicro" (at -0.4 -3.901) (layer "B.Fab") hide
      (effects (font (size 0.7 0.7) (thickness 0.15)) (justify left bottom mirror))
    )
    (fp_text user "License: Apache-2.0" (at -0.4 -5.101) (layer "B.Fab") hide
      (effects (font (size 0.7 0.7) (thickness 0.15)) (justify left bottom mirror))
    )
    (pad "1" smd circle (at 0 0 180) (size 0.75 0.75) (layers "B.Cu" "B.Mask")
      (net 1 "GND") (pinfunction "1") (pintype "passive"))
  )
	(footprint "sa800u-baseboard-hw-footprints:TP_SMD_0.75mm" (layer "B.Cu")
    (tedit 5E4A9375)
    (at 59 101.5 90)
    (property "Author" "Antmicro")
    (property "License" "Apache-2.0")
    (property "MPN" "")
    (property "Manufacturer" "")
    (property "Sheetfile" "poe.kicad_sch")
    (property "Sheetname" "PoE")
    (attr smd)
    (fp_text reference "TP78" (at 2.99 0.42 270) (layer "B.SilkS")
      (effects (font (size 0.7 0.7) (thickness 0.15)) (justify left bottom mirror))
    )
    (fp_text value "TP_0.75mm_SMD" (at 0 -1.2 270) (layer "B.Fab")
      (effects (font (size 0.7 0.7) (thickness 0.15)) (justify left bottom mirror))
    )
    (fp_text user "License: Apache-2.0" (at -0.4 -5.101 270) (layer "B.Fab") hide
      (effects (font (size 0.7 0.7) (thickness 0.15)) (justify left bottom mirror))
    )
    (fp_text user "${REFERENCE}" (at -0.4 -2.7 270) (layer "B.Fab") hide
      (effects (font (size 0.7 0.7) (thickness 0.15)) (justify left bottom mirror))
    )
    (fp_text user "Author: Antmicro" (at -0.4 -3.901 270) (layer "B.Fab") hide
      (effects (font (size 0.7 0.7) (thickness 0.15)) (justify left bottom mirror))
    )
    (pad "1" smd circle (at 0 0 90) (size 0.75 0.75) (layers "B.Cu" "B.Mask")
      (net 73 "/PoE/VDD_POE") (pinfunction "1") (pintype "passive"))
  )
	(footprint "sa800u-baseboard-hw-footprints:TP_SMD_0.75mm" (layer "B.Cu")
    (tedit 5E4A9375)
    (at 56.5 109.25 90)
    (property "Author" "Antmicro")
    (property "License" "Apache-2.0")
    (property "MPN" "")
    (property "Manufacturer" "")
    (property "Sheetfile" "poe.kicad_sch")
    (property "Sheetname" "PoE")
    (attr smd)
    (fp_text reference "TP79" (at 0.48 1.33) (layer "B.SilkS")
      (effects (font (size 0.7 0.7) (thickness 0.15)) (justify left bottom mirror))
    )
    (fp_text value "TP_0.75mm_SMD" (at 0 -1.2 270) (layer "B.Fab")
      (effects (font (size 0.7 0.7) (thickness 0.15)) (justify left bottom mirror))
    )
    (fp_text user "Author: Antmicro" (at -0.4 -3.901 270) (layer "B.Fab") hide
      (effects (font (size 0.7 0.7) (thickness 0.15)) (justify left bottom mirror))
    )
    (fp_text user "${REFERENCE}" (at -0.4 -2.7 270) (layer "B.Fab") hide
      (effects (font (size 0.7 0.7) (thickness 0.15)) (justify left bottom mirror))
    )
    (fp_text user "License: Apache-2.0" (at -0.4 -5.101 270) (layer "B.Fab") hide
      (effects (font (size 0.7 0.7) (thickness 0.15)) (justify left bottom mirror))
    )
    (pad "1" smd circle (at 0 0 90) (size 0.75 0.75) (layers "B.Cu" "B.Mask")
      (net 135 "/PoE/VSS_POE") (pinfunction "1") (pintype "passive"))
  )
	(footprint "sa800u-baseboard-hw-footprints:TP_SMD_0.75mm" (layer "B.Cu")
    (tedit 5E4A9375)
    (at 56.5 101.5 90)
    (property "Author" "Antmicro")
    (property "License" "Apache-2.0")
    (property "MPN" "")
    (property "Manufacturer" "")
    (property "Sheetfile" "poe.kicad_sch")
    (property "Sheetname" "PoE")
    (attr smd)
    (fp_text reference "TP80" (at 3.02 0.38 270) (layer "B.SilkS")
      (effects (font (size 0.7 0.7) (thickness 0.15)) (justify left bottom mirror))
    )
    (fp_text value "TP_0.75mm_SMD" (at 0 -1.2 270) (layer "B.Fab")
      (effects (font (size 0.7 0.7) (thickness 0.15)) (justify left bottom mirror))
    )
    (fp_text user "${REFERENCE}" (at -0.4 -2.7 270) (layer "B.Fab") hide
      (effects (font (size 0.7 0.7) (thickness 0.15)) (justify left bottom mirror))
    )
    (fp_text user "Author: Antmicro" (at -0.4 -3.901 270) (layer "B.Fab") hide
      (effects (font (size 0.7 0.7) (thickness 0.15)) (justify left bottom mirror))
    )
    (fp_text user "License: Apache-2.0" (at -0.4 -5.101 270) (layer "B.Fab") hide
      (effects (font (size 0.7 0.7) (thickness 0.15)) (justify left bottom mirror))
    )
    (pad "1" smd circle (at 0 0 90) (size 0.75 0.75) (layers "B.Cu" "B.Mask")
      (net 384 "Net-(IC2-Pad7)") (pinfunction "1") (pintype "passive"))
  )
	(footprint "sa800u-baseboard-hw-footprints:TP_SMD_0.75mm" (layer "B.Cu")
    (tedit 5E4A9375)
    (at 61.515 101.32 90)
    (property "Author" "Antmicro")
    (property "License" "Apache-2.0")
    (property "MPN" "")
    (property "Manufacturer" "")
    (property "Sheetfile" "poe.kicad_sch")
    (property "Sheetname" "PoE")
    (attr smd)
    (fp_text reference "TP82" (at 3.07 0.39 90) (layer "B.SilkS")
      (effects (font (size 0.7 0.7) (thickness 0.15)) (justify left bottom mirror))
    )
    (fp_text value "TP_0.75mm_SMD" (at 0 -1.2 270) (layer "B.Fab")
      (effects (font (size 0.7 0.7) (thickness 0.15)) (justify left bottom mirror))
    )
    (fp_text user "${REFERENCE}" (at -0.4 -2.7 270) (layer "B.Fab") hide
      (effects (font (size 0.7 0.7) (thickness 0.15)) (justify left bottom mirror))
    )
    (fp_text user "License: Apache-2.0" (at -0.4 -5.101 270) (layer "B.Fab") hide
      (effects (font (size 0.7 0.7) (thickness 0.15)) (justify left bottom mirror))
    )
    (fp_text user "Author: Antmicro" (at -0.4 -3.901 270) (layer "B.Fab") hide
      (effects (font (size 0.7 0.7) (thickness 0.15)) (justify left bottom mirror))
    )
    (pad "1" smd circle (at 0 0 90) (size 0.75 0.75) (layers "B.Cu" "B.Mask")
      (net 76 "/PoE/SMPS_CTRL") (pinfunction "1") (pintype "passive"))
  )
	(footprint "sa800u-baseboard-hw-footprints:TP_SMD_0.75mm" (layer "B.Cu")
    (tedit 5E4A9375)
    (at 56.5 104)
    (property "Author" "Antmicro")
    (property "License" "Apache-2.0")
    (property "MPN" "")
    (property "Manufacturer" "")
    (property "Sheetfile" "poe.kicad_sch")
    (property "Sheetname" "PoE")
    (attr smd)
    (fp_text reference "TP81" (at 1.32 1.2 180) (layer "B.SilkS")
      (effects (font (size 0.7 0.7) (thickness 0.15)) (justify left bottom mirror))
    )
    (fp_text value "TP_0.75mm_SMD" (at 0 -1.2 180) (layer "B.Fab")
      (effects (font (size 0.7 0.7) (thickness 0.15)) (justify left bottom mirror))
    )
    (fp_text user "${REFERENCE}" (at -0.4 -2.7 180) (layer "B.Fab") hide
      (effects (font (size 0.7 0.7) (thickness 0.15)) (justify left bottom mirror))
    )
    (fp_text user "License: Apache-2.0" (at -0.4 -5.101 180) (layer "B.Fab") hide
      (effects (font (size 0.7 0.7) (thickness 0.15)) (justify left bottom mirror))
    )
    (fp_text user "Author: Antmicro" (at -0.4 -3.901 180) (layer "B.Fab") hide
      (effects (font (size 0.7 0.7) (thickness 0.15)) (justify left bottom mirror))
    )
    (pad "1" smd circle (at 0 0) (size 0.75 0.75) (layers "B.Cu" "B.Mask")
      (net 7 "GNDD") (pinfunction "1") (pintype "passive"))
  )
	(footprint "sa800u-baseboard-hw-footprints:R_0402_1005Metric" (layer "B.Cu")
    (tedit 5FD9C158)
    (at 120.6 133.5 -90)
    (descr "Resistor SMD 0402")
    (tags "resistor SMD 0402")
    (property "Author" "Antmicro")
    (property "License" "Apache-2.0")
    (property "MPN" "CR0402-FX-2003GLF")
    (property "Manufacturer" "Bourns")
    (property "Sheetfile" "usb-c-interface.kicad_sch")
    (property "Sheetname" "USB-C Interface ")
    (property "Tolerance" "1%")
    (property "Val" "200k")
    (attr smd)
    (fp_text reference "R64" (at -1.091 -2.34 90) (layer "B.SilkS")
      (effects (font (size 0.7 0.7) (thickness 0.15)) (justify left bottom mirror))
    )
    (fp_text value "R_200k_0402" (at 0 -1.4 90) (layer "B.Fab")
      (effects (font (size 0.7 0.7) (thickness 0.15)) (justify left bottom mirror))
    )
    (fp_text user "${REFERENCE}" (at -0.95 -3.168 90) (layer "B.Fab") hide
      (effects (font (size 0.7 0.7) (thickness 0.15)) (justify left bottom mirror))
    )
    (fp_text user "License: Apache-2.0" (at -0.95 -5.169 90) (layer "B.Fab") hide
      (effects (font (size 0.7 0.7) (thickness 0.15)) (justify left bottom mirror))
    )
    (fp_text user "Author: Antmicro" (at -0.95 -4.169 90) (layer "B.Fab") hide
      (effects (font (size 0.7 0.7) (thickness 0.15)) (justify left bottom mirror))
    )
    (fp_rect (start -0.93 0.47) (end 0.93 -0.47) (layer "B.CrtYd") (width 0.05) (fill none))
    (fp_rect (start -0.5 0.25) (end 0.5 -0.25) (layer "B.Fab") (width 0.15) (fill none))
    (pad "1" smd roundrect (at -0.485 0 270) (size 0.59 0.64) (layers "B.Cu" "B.Paste" "B.Mask") (roundrect_rratio 0.25)
      (net 290 "/USB-C Interface /USB2_CC_SELECT") (pintype "passive"))
    (pad "2" smd roundrect (at 0.485 0 270) (size 0.59 0.64) (layers "B.Cu" "B.Paste" "B.Mask") (roundrect_rratio 0.25)
      (net 1 "GND") (pintype "passive"))
  )
	(footprint "sa800u-baseboard-hw-footprints:L_0603_1608Metric" (layer "B.Cu")
    (tedit 5D5D3F54)
    (at 134.000003 120.766849)
    (property "Author" "Antmicro")
    (property "IMax" "")
    (property "ISat" "")
    (property "License" "Apache-2.0")
    (property "MPN" "BRC1608TR35M")
    (property "Manufacturer" "Taiyo Yuden")
    (property "Sheetfile" "hdmi-converter.kicad_sch")
    (property "Sheetname" "HDMI converter")
    (property "Size" "")
    (property "Val" "350n/1.4A")
    (attr smd)
    (fp_text reference "L4" (at 0.669997 -0.896849 180) (layer "B.SilkS")
      (effects (font (size 0.7 0.7) (thickness 0.15)) (justify left bottom mirror))
    )
    (fp_text value "L_350n_1.4A_0603" (at 0 -2 180) (layer "B.Fab")
      (effects (font (size 0.7 0.7) (thickness 0.15)) (justify left bottom mirror))
    )
    (fp_text user "License: Apache-2.0" (at -1.9 -5.75 180) (layer "B.Fab") hide
      (effects (font (size 0.7 0.7) (thickness 0.15)) (justify left bottom mirror))
    )
    (fp_text user "Author: Antmicro" (at -1.9 -4.4 180) (layer "B.Fab") hide
      (effects (font (size 0.7 0.7) (thickness 0.15)) (justify left bottom mirror))
    )
    (fp_text user "${REFERENCE}" (at -1.9 -3.1 180) (layer "B.Fab") hide
      (effects (font (size 0.7 0.7) (thickness 0.15)) (justify left bottom mirror))
    )
    (fp_line (start -0.25 -0.45) (end 0.25 -0.45) (layer "B.SilkS") (width 0.1))
    (fp_line (start -0.25 0.45) (end 0.25 0.45) (layer "B.SilkS") (width 0.1))
    (fp_rect (start -1.15 0.75) (end 1.15 -0.75) (layer "B.CrtYd") (width 0.05) (fill none))
    (fp_rect (start -0.8 0.4) (end 0.8 -0.4) (layer "B.Fab") (width 0.1) (fill none))
    (pad "1" smd roundrect (at -0.625 0) (size 0.55 1) (layers "B.Cu" "B.Paste" "B.Mask") (roundrect_rratio 0.15)
      (net 138 "1V2_SYS") (pintype "passive"))
    (pad "2" smd roundrect (at 0.625 0) (size 0.55 1) (layers "B.Cu" "B.Paste" "B.Mask") (roundrect_rratio 0.15)
      (net 188 "/HDMI converter/LT9611_VDD12") (pintype "passive"))
  )
	(footprint "sa800u-baseboard-hw-footprints:TP_SMD_0.75mm" (layer "B.Cu")
    (tedit 5E4A9375)
    (at 134 127.6)
    (property "Author" "Antmicro")
    (property "License" "Apache-2.0")
    (property "MPN" "")
    (property "Manufacturer" "")
    (property "Sheetfile" "hdmi-converter.kicad_sch")
    (property "Sheetname" "HDMI converter")
    (attr smd)
    (fp_text reference "TP27" (at -0.31 0.52 180) (layer "B.SilkS")
      (effects (font (size 0.7 0.7) (thickness 0.15)) (justify left bottom mirror))
    )
    (fp_text value "TP_0.75mm_SMD" (at 0 -1.2 180) (layer "B.Fab")
      (effects (font (size 0.7 0.7) (thickness 0.15)) (justify left bottom mirror))
    )
    (fp_text user "Author: Antmicro" (at -0.4 -3.901 180) (layer "B.Fab") hide
      (effects (font (size 0.7 0.7) (thickness 0.15)) (justify left bottom mirror))
    )
    (fp_text user "${REFERENCE}" (at -0.4 -2.7 180) (layer "B.Fab") hide
      (effects (font (size 0.7 0.7) (thickness 0.15)) (justify left bottom mirror))
    )
    (fp_text user "License: Apache-2.0" (at -0.4 -5.101 180) (layer "B.Fab") hide
      (effects (font (size 0.7 0.7) (thickness 0.15)) (justify left bottom mirror))
    )
    (pad "1" smd circle (at 0 0) (size 0.75 0.75) (layers "B.Cu" "B.Mask")
      (net 1 "GND") (pinfunction "1") (pintype "passive"))
  )
	(footprint "sa800u-baseboard-hw-footprints:TP_SMD_0.75mm" (layer "B.Cu")
    (tedit 5E4A9375)
    (at 78.2 124)
    (property "Author" "Antmicro")
    (property "License" "Apache-2.0")
    (property "MPN" "")
    (property "Manufacturer" "")
    (property "Sheetfile" "psu.kicad_sch")
    (property "Sheetname" "PSU")
    (attr smd)
    (fp_text reference "TP54" (at -0.21 1.06 180) (layer "B.SilkS")
      (effects (font (size 0.7 0.7) (thickness 0.15)) (justify left bottom mirror))
    )
    (fp_text value "TP_0.75mm_SMD" (at 0 -1.2 180) (layer "B.Fab")
      (effects (font (size 0.7 0.7) (thickness 0.15)) (justify left bottom mirror))
    )
    (fp_text user "${REFERENCE}" (at -0.4 -2.7 180) (layer "B.Fab") hide
      (effects (font (size 0.7 0.7) (thickness 0.15)) (justify left bottom mirror))
    )
    (fp_text user "Author: Antmicro" (at -0.4 -3.901 180) (layer "B.Fab") hide
      (effects (font (size 0.7 0.7) (thickness 0.15)) (justify left bottom mirror))
    )
    (fp_text user "License: Apache-2.0" (at -0.4 -5.101 180) (layer "B.Fab") hide
      (effects (font (size 0.7 0.7) (thickness 0.15)) (justify left bottom mirror))
    )
    (pad "1" smd circle (at 0 0) (size 0.75 0.75) (layers "B.Cu" "B.Mask")
      (net 340 "/PSU/POE_VALID") (pinfunction "1") (pintype "passive"))
  )
	(footprint "sa800u-baseboard-hw-footprints:TP_SMD_0.75mm" (layer "B.Cu")
    (tedit 5E4A9375)
    (at 78.18 125.55)
    (property "Author" "Antmicro")
    (property "License" "Apache-2.0")
    (property "MPN" "")
    (property "Manufacturer" "")
    (property "Sheetfile" "psu.kicad_sch")
    (property "Sheetname" "PSU")
    (attr smd)
    (fp_text reference "TP55" (at -0.32 0.54 180) (layer "B.SilkS")
      (effects (font (size 0.7 0.7) (thickness 0.15)) (justify left bottom mirror))
    )
    (fp_text value "TP_0.75mm_SMD" (at 0 -1.2 180) (layer "B.Fab")
      (effects (font (size 0.7 0.7) (thickness 0.15)) (justify left bottom mirror))
    )
    (fp_text user "License: Apache-2.0" (at -0.4 -5.101 180) (layer "B.Fab") hide
      (effects (font (size 0.7 0.7) (thickness 0.15)) (justify left bottom mirror))
    )
    (fp_text user "${REFERENCE}" (at -0.4 -2.7 180) (layer "B.Fab") hide
      (effects (font (size 0.7 0.7) (thickness 0.15)) (justify left bottom mirror))
    )
    (fp_text user "Author: Antmicro" (at -0.4 -3.901 180) (layer "B.Fab") hide
      (effects (font (size 0.7 0.7) (thickness 0.15)) (justify left bottom mirror))
    )
    (pad "1" smd circle (at 0 0) (size 0.75 0.75) (layers "B.Cu" "B.Mask")
      (net 341 "/PSU/USB_PD_VALID") (pinfunction "1") (pintype "passive"))
  )
	(footprint "sa800u-baseboard-hw-footprints:TP_SMD_0.75mm" (layer "B.Cu")
    (tedit 5E4A9375)
    (at 76 130.25)
    (property "Author" "Antmicro")
    (property "License" "Apache-2.0")
    (property "MPN" "")
    (property "Manufacturer" "")
    (property "Sheetfile" "psu.kicad_sch")
    (property "Sheetname" "PSU")
    (attr smd)
    (fp_text reference "TP56" (at 1.22 -0.47 180) (layer "B.SilkS")
      (effects (font (size 0.7 0.7) (thickness 0.15)) (justify left bottom mirror))
    )
    (fp_text value "TP_0.75mm_SMD" (at 0 -1.2 180) (layer "B.Fab")
      (effects (font (size 0.7 0.7) (thickness 0.15)) (justify left bottom mirror))
    )
    (fp_text user "${REFERENCE}" (at -0.4 -2.7 180) (layer "B.Fab") hide
      (effects (font (size 0.7 0.7) (thickness 0.15)) (justify left bottom mirror))
    )
    (fp_text user "License: Apache-2.0" (at -0.4 -5.101 180) (layer "B.Fab") hide
      (effects (font (size 0.7 0.7) (thickness 0.15)) (justify left bottom mirror))
    )
    (fp_text user "Author: Antmicro" (at -0.4 -3.901 180) (layer "B.Fab") hide
      (effects (font (size 0.7 0.7) (thickness 0.15)) (justify left bottom mirror))
    )
    (pad "1" smd circle (at 0 0) (size 0.75 0.75) (layers "B.Cu" "B.Mask")
      (net 74 "VDD") (pinfunction "1") (pintype "passive"))
  )
)
